(kicad_pcb
	(version 20241229)
	(generator "pcbnew")
	(generator_version "9.0")
	(general
		(thickness 1.61)
		(legacy_teardrops no)
	)
	(paper "A3")
	(title_block
		(title "SO-DIMM DDR5 Tester")
		(date "2025-11-26")
		(rev "1.3.0")
		(comment 9 "footprints 288-290 of 627")
	)
	(layers
		(0 "F.Cu" signal)
		(4 "In1.Cu" power)
		(6 "In2.Cu" mixed)
		(8 "In3.Cu" power)
		(10 "In4.Cu" mixed)
		(12 "In5.Cu" power)
		(14 "In6.Cu" mixed)
		(16 "In7.Cu" power)
		(18 "In8.Cu" power)
		(20 "In9.Cu" mixed)
		(22 "In10.Cu" power)
		(2 "B.Cu" signal)
		(9 "F.Adhes" user "F.Adhesive")
		(11 "B.Adhes" user "B.Adhesive")
		(13 "F.Paste" user)
		(15 "B.Paste" user)
		(5 "F.SilkS" user "F.Silkscreen")
		(7 "B.SilkS" user "B.Silkscreen")
		(1 "F.Mask" user)
		(3 "B.Mask" user)
		(17 "Dwgs.User" user "User.Drawings")
		(19 "Cmts.User" user "User.Comments")
		(21 "Eco1.User" user "User.Eco1")
		(23 "Eco2.User" user "User.Eco2")
		(25 "Edge.Cuts" user)
		(27 "Margin" user)
		(31 "F.CrtYd" user "F.Courtyard")
		(29 "B.CrtYd" user "B.Courtyard")
		(35 "F.Fab" user)
		(33 "B.Fab" user)
	)
	(footprint "antmicro-footprints:R_0402_1005Metric"
		(layer "F.Cu")
		(at 114.4 186.6 -90)
		(descr "Resistor SMD 0402")
		(tags "resistor SMD 0402")
		(property "Reference" "R6"
			(at -1.122484 -0.772697 270)
			(layer "F.SilkS")
			(hide yes)
			(effects
				(font
					(size 0.7 0.7)
					(thickness 0.15)
				)
				(justify left bottom)
			)
		)
		(property "Value" "R_22R_0402"
			(at -1.011843 1.772047 270)
			(layer "F.Fab")
			(effects
				(font
					(size 0.7 0.7)
					(thickness 0.15)
				)
				(justify left bottom)
			)
		)
		(property "Datasheet" "https://www.bourns.com/docs/product-datasheets/cr.pdf"
			(at 0 0 270)
			(layer "F.Fab")
			(hide yes)
			(effects
				(font
					(size 1.27 1.27)
					(thickness 0.15)
				)
			)
		)
		(property "Author" "Antmicro"
			(at -72.2 301 0)
			(layer "F.Fab")
			(hide yes)
			(effects
				(font
					(size 1 1)
					(thickness 0.15)
				)
			)
		)
		(property "License" "Apache-2.0"
			(at -72.2 301 0)
			(layer "F.Fab")
			(hide yes)
			(effects
				(font
					(size 1 1)
					(thickness 0.15)
				)
			)
		)
		(property "MPN" "CR0402-FX-22R0GLF"
			(at -72.2 301 0)
			(layer "F.Fab")
			(hide yes)
			(effects
				(font
					(size 1 1)
					(thickness 0.15)
				)
			)
		)
		(property "Manufacturer" "Bourns"
			(at -72.2 301 0)
			(layer "F.Fab")
			(hide yes)
			(effects
				(font
					(size 1 1)
					(thickness 0.15)
				)
			)
		)
		(property "Tolerance" "1%"
			(at -72.2 301 0)
			(layer "F.Fab")
			(hide yes)
			(effects
				(font
					(size 1 1)
					(thickness 0.15)
				)
			)
		)
		(property "Val" "22R"
			(at -72.2 301 0)
			(layer "F.Fab")
			(hide yes)
			(effects
				(font
					(size 1 1)
					(thickness 0.15)
				)
			)
		)
		(sheetname "/HyperRAM + QSPI Flash/")
		(sheetfile "hyperram-flash.kicad_sch")
		(attr smd)
		(fp_rect
			(start -0.93 -0.47)
			(end 0.93 0.47)
			(stroke
				(width 0.05)
				(type solid)
			)
			(fill no)
			(layer "F.CrtYd")
		)
		(fp_rect
			(start -0.5 -0.25)
			(end 0.5 0.25)
			(stroke
				(width 0.15)
				(type solid)
			)
			(fill no)
			(layer "F.Fab")
		)
		(pad "1" smd roundrect
			(at -0.485 0 270)
			(size 0.59 0.64)
			(layers "F.Cu" "F.Mask" "F.Paste")
			(roundrect_rratio 0.25)
			(net 362 "/HyperRAM + QSPI Flash/IO0")
			(pintype "passive")
		)
		(pad "2" smd roundrect
			(at 0.485 0 270)
			(size 0.59 0.64)
			(layers "F.Cu" "F.Mask" "F.Paste")
			(roundrect_rratio 0.25)
			(net 626 "/FPGA Config/FLASH.IO0")
			(pintype "passive")
		)
	)
	(footprint "antmicro-footprints:USB-C_Receptacle_GCT_USB4105-GF-A"
		(layer "F.Cu")
		(at 71.700501 155.316 -90)
		(property "Reference" "J3"
			(at 6.084 2.600501 0)
			(layer "F.SilkS")
			(effects
				(font
					(size 0.7 0.7)
					(thickness 0.15)
				)
				(justify left bottom)
			)
		)
		(property "Value" "USB-C_GCT_USB4105-GF-A"
			(at 0 5 270)
			(layer "F.Fab")
			(effects
				(font
					(size 0.7 0.7)
					(thickness 0.15)
				)
				(justify left bottom)
			)
		)
		(property "Datasheet" "https://gct.co/files/drawings/usb4105.pdf"
			(at 0 0 270)
			(layer "F.Fab")
			(hide yes)
			(effects
				(font
					(size 1.27 1.27)
					(thickness 0.15)
				)
			)
		)
		(property "Author" "Antmicro"
			(at -83.615499 227.016501 0)
			(layer "F.Fab")
			(hide yes)
			(effects
				(font
					(size 1 1)
					(thickness 0.15)
				)
			)
		)
		(property "License" "Apache-2.0"
			(at -83.615499 227.016501 0)
			(layer "F.Fab")
			(hide yes)
			(effects
				(font
					(size 1 1)
					(thickness 0.15)
				)
			)
		)
		(property "MPN" "USB4105-GF-A"
			(at -83.615499 227.016501 0)
			(layer "F.Fab")
			(hide yes)
			(effects
				(font
					(size 1 1)
					(thickness 0.15)
				)
			)
		)
		(property "Manufacturer" "GCT"
			(at -83.615499 227.016501 0)
			(layer "F.Fab")
			(hide yes)
			(effects
				(font
					(size 1 1)
					(thickness 0.15)
				)
			)
		)
		(property "VSD_Class" "USB-C"
			(at -83.615499 227.016501 0)
			(layer "F.Fab")
			(hide yes)
			(effects
				(font
					(size 1 1)
					(thickness 0.15)
				)
			)
		)
		(sheetname "/Debug FTDI/")
		(sheetfile "debug-ftdi.kicad_sch")
		(attr smd)
		(fp_line
			(start -4.79 3.854)
			(end 4.788 3.854)
			(stroke
				(width 0.15)
				(type solid)
			)
			(layer "F.SilkS")
		)
		(fp_line
			(start 4.788 3.854)
			(end 4.788 2.575)
			(stroke
				(width 0.15)
				(type solid)
			)
			(layer "F.SilkS")
		)
		(fp_line
			(start -4.79 2.575)
			(end -4.79 3.854)
			(stroke
				(width 0.15)
				(type solid)
			)
			(layer "F.SilkS")
		)
		(fp_line
			(start -4.79 -1.395)
			(end -4.79 -0.145)
			(stroke
				(width 0.15)
				(type solid)
			)
			(layer "F.SilkS")
		)
		(fp_line
			(start 4.788 -1.395)
			(end 4.788 -0.145)
			(stroke
				(width 0.15)
				(type solid)
			)
			(layer "F.SilkS")
		)
		(fp_circle
			(center -3.8 -4.27071)
			(end -3.75 -4.22071)
			(stroke
				(width 0.15)
				(type solid)
			)
			(fill yes)
			(layer "F.SilkS")
		)
		(fp_rect
			(start -5.1 -4.4)
			(end 5.1 3.9)
			(stroke
				(width 0.05)
				(type solid)
			)
			(fill no)
			(layer "F.CrtYd")
		)
		(fp_line
			(start -4.79 3.854)
			(end -4.79 -3.676)
			(stroke
				(width 0.15)
				(type solid)
			)
			(layer "F.Fab")
		)
		(fp_line
			(start -4.702 3.854)
			(end 4.788 3.854)
			(stroke
				(width 0.15)
				(type solid)
			)
			(layer "F.Fab")
		)
		(fp_line
			(start 4.788 3.854)
			(end -4.79 3.854)
			(stroke
				(width 0.15)
				(type solid)
			)
			(layer "F.Fab")
		)
		(fp_line
			(start -4.79 -3.676)
			(end 4.788 -3.676)
			(stroke
				(width 0.15)
				(type solid)
			)
			(layer "F.Fab")
		)
		(fp_line
			(start 4.788 -3.676)
			(end 4.788 3.854)
			(stroke
				(width 0.15)
				(type solid)
			)
			(layer "F.Fab")
		)
		(pad "" np_thru_hole circle
			(at -2.891 -2.426 270)
			(size 0.65 0.65)
			(drill 0.65)
			(layers "*.Cu" "*.Mask")
		)
		(pad "" np_thru_hole circle
			(at 2.89 -2.426 270)
			(size 0.65 0.65)
			(drill 0.65)
			(layers "*.Cu" "*.Mask")
		)
		(pad "A1" smd roundrect
			(at -3.202 -3.5 270)
			(size 0.6 1.15)
			(layers "F.Cu" "F.Mask" "F.Paste")
			(roundrect_rratio 0.25)
			(net 1 "GND")
			(pinfunction "GND")
			(pintype "power_in")
		)
		(pad "A4" smd roundrect
			(at -2.4 -3.5 270)
			(size 0.6 1.15)
			(layers "F.Cu" "F.Mask" "F.Paste")
			(roundrect_rratio 0.25)
			(net 2 "/Debug FTDI/VBUS")
			(pinfunction "VBUS")
			(pintype "passive")
		)
		(pad "A5" smd roundrect
			(at -1.25 -3.5 270)
			(size 0.3 1.15)
			(layers "F.Cu" "F.Mask" "F.Paste")
			(roundrect_rratio 0.25)
			(net 321 "Net-(J3-CC_{1})")
			(pinfunction "CC_{1}")
			(pintype "bidirectional")
		)
		(pad "A6" smd roundrect
			(at -0.25 -3.5 270)
			(size 0.3 1.15)
			(layers "F.Cu" "F.Mask" "F.Paste")
			(roundrect_rratio 0.25)
			(net 290 "/Debug FTDI/DBG_USB_P")
			(pinfunction "D_{A}+")
			(pintype "bidirectional")
		)
		(pad "A7" smd roundrect
			(at 0.248 -3.5 270)
			(size 0.3 1.15)
			(layers "F.Cu" "F.Mask" "F.Paste")
			(roundrect_rratio 0.25)
			(net 291 "/Debug FTDI/DBG_USB_N")
			(pinfunction "D_{A}-")
			(pintype "bidirectional")
		)
		(pad "A8" smd roundrect
			(at 1.249 -3.5 270)
			(size 0.3 1.15)
			(layers "F.Cu" "F.Mask" "F.Paste")
			(roundrect_rratio 0.25)
			(net 322 "unconnected-(J3-SBU_{1}-PadA8)")
			(pinfunction "SBU_{1}")
			(pintype "bidirectional+no_connect")
		)
		(pad "A9" smd roundrect
			(at 2.398 -3.5 270)
			(size 0.6 1.15)
			(layers "F.Cu" "F.Mask" "F.Paste")
			(roundrect_rratio 0.25)
			(net 2 "/Debug FTDI/VBUS")
			(pinfunction "VBUS")
			(pintype "passive")
		)
		(pad "A12" smd roundrect
			(at 3.2 -3.5 270)
			(size 0.6 1.15)
			(layers "F.Cu" "F.Mask" "F.Paste")
			(roundrect_rratio 0.25)
			(net 1 "GND")
			(pinfunction "GND")
			(pintype "passive")
		)
		(pad "B1" smd roundrect
			(at 3.2 -3.5 270)
			(size 0.6 1.15)
			(layers "F.Cu" "F.Mask" "F.Paste")
			(roundrect_rratio 0.25)
			(net 1 "GND")
			(pinfunction "GND")
			(pintype "passive")
		)
		(pad "B4" smd roundrect
			(at 2.398 -3.5 270)
			(size 0.6 1.15)
			(layers "F.Cu" "F.Mask" "F.Paste")
			(roundrect_rratio 0.25)
			(net 2 "/Debug FTDI/VBUS")
			(pinfunction "VBUS")
			(pintype "passive")
		)
		(pad "B5" smd roundrect
			(at 1.749 -3.5 270)
			(size 0.3 1.15)
			(layers "F.Cu" "F.Mask" "F.Paste")
			(roundrect_rratio 0.25)
			(net 323 "Net-(J3-CC_{2})")
			(pinfunction "CC_{2}")
			(pintype "bidirectional")
		)
		(pad "B6" smd roundrect
			(at 0.748 -3.5 270)
			(size 0.3 1.15)
			(layers "F.Cu" "F.Mask" "F.Paste")
			(roundrect_rratio 0.25)
			(net 290 "/Debug FTDI/DBG_USB_P")
			(pinfunction "D_{B}+")
			(pintype "bidirectional")
		)
		(pad "B7" smd roundrect
			(at -0.75 -3.5 270)
			(size 0.3 1.15)
			(layers "F.Cu" "F.Mask" "F.Paste")
			(roundrect_rratio 0.25)
			(net 291 "/Debug FTDI/DBG_USB_N")
			(pinfunction "D_{B}-")
			(pintype "bidirectional")
		)
		(pad "B8" smd roundrect
			(at -1.75 -3.5 270)
			(size 0.3 1.15)
			(layers "F.Cu" "F.Mask" "F.Paste")
			(roundrect_rratio 0.25)
			(net 324 "unconnected-(J3-SBU_{2}-PadB8)")
			(pinfunction "SBU_{2}")
			(pintype "bidirectional+no_connect")
		)
		(pad "B9" smd roundrect
			(at -2.4 -3.5 270)
			(size 0.6 1.15)
			(layers "F.Cu" "F.Mask" "F.Paste")
			(roundrect_rratio 0.25)
			(net 2 "/Debug FTDI/VBUS")
			(pinfunction "VBUS")
			(pintype "passive")
		)
		(pad "B12" smd roundrect
			(at -3.202 -3.5 270)
			(size 0.6 1.15)
			(layers "F.Cu" "F.Mask" "F.Paste")
			(roundrect_rratio 0.25)
			(net 1 "GND")
			(pinfunction "GND")
			(pintype "passive")
		)
		(pad "SH" thru_hole oval
			(at -4.321 -2.926 270)
			(size 1.05 2.1)
			(drill oval 0.6 1.7)
			(layers "*.Cu" "*.Mask")
			(remove_unused_layers no)
			(net 593 "Net-(C133-Pad1)")
			(pinfunction "SH")
			(pintype "passive")
		)
		(pad "SH" thru_hole oval
			(at -4.321 1.255 270)
			(size 1 2)
			(drill oval 0.6 1.4)
			(layers "*.Cu" "*.Mask")
			(remove_unused_layers no)
			(net 593 "Net-(C133-Pad1)")
			(pinfunction "SH")
			(pintype "passive")
		)
		(pad "SH" thru_hole oval
			(at 4.32 -2.926 270)
			(size 1.05 2.1)
			(drill oval 0.6 1.7)
			(layers "*.Cu" "*.Mask")
			(remove_unused_layers no)
			(net 593 "Net-(C133-Pad1)")
			(pinfunction "SH")
			(pintype "passive")
		)
		(pad "SH" thru_hole oval
			(at 4.32 1.255 270)
			(size 1 2)
			(drill oval 0.6 1.4)
			(layers "*.Cu" "*.Mask")
			(remove_unused_layers no)
			(net 593 "Net-(C133-Pad1)")
			(pinfunction "SH")
			(pintype "passive")
		)
	)
	(footprint "antmicro-footprints:DHVQFN-14-1EP_2.5x3mm"
		(layer "F.Cu")
		(at 93.9 181.7 -90)
		(property "Reference" "U7"
			(at 1.9 3.4 0)
			(layer "F.SilkS")
			(effects
				(font
					(size 0.7 0.7)
					(thickness 0.15)
				)
				(justify left bottom)
			)
		)
		(property "Value" "TXU0304BQAR"
			(at 0 2.898 270)
			(layer "F.Fab")
			(effects
				(font
					(size 0.7 0.7)
					(thickness 0.15)
				)
				(justify left bottom)
			)
		)
		(property "Datasheet" "https://www.ti.com/lit/ds/symlink/txu0304.pdf?ts=1637748643258&ref_url=https%253A%252F%252Fwww.ti.com%252Fproduct%252FTXU0304"
			(at 0 0 270)
			(layer "F.Fab")
			(hide yes)
			(effects
				(font
					(size 1.27 1.27)
					(thickness 0.15)
				)
			)
		)
		(property "Author" "Antmicro"
			(at -87.8 275.6 0)
			(layer "F.Fab")
			(hide yes)
			(effects
				(font
					(size 1 1)
					(thickness 0.15)
				)
			)
		)
		(property "License" "Apache-2.0"
			(at -87.8 275.6 0)
			(layer "F.Fab")
			(hide yes)
			(effects
				(font
					(size 1 1)
					(thickness 0.15)
				)
			)
		)
		(property "MPN" "TXU0304BQAR"
			(at -87.8 275.6 0)
			(layer "F.Fab")
			(hide yes)
			(effects
				(font
					(size 1 1)
					(thickness 0.15)
				)
			)
		)
		(property "Manufacturer" "Texas Instruments"
			(at -87.8 275.6 0)
			(layer "F.Fab")
			(hide yes)
			(effects
				(font
					(size 1 1)
					(thickness 0.15)
				)
			)
		)
		(sheetname "/Debug FTDI/")
		(sheetfile "debug-ftdi.kicad_sch")
		(attr smd)
		(fp_line
			(start -1.351 1.6)
			(end -0.5 1.6)
			(stroke
				(width 0.15)
				(type solid)
			)
			(layer "F.SilkS")
		)
		(fp_line
			(start -1.351 1.6)
			(end -1.351 1.249)
			(stroke
				(width 0.15)
				(type solid)
			)
			(layer "F.SilkS")
		)
		(fp_line
			(start 0.494 1.6)
			(end 1.35 1.6)
			(stroke
				(width 0.15)
				(type solid)
			)
			(layer "F.SilkS")
		)
		(fp_line
			(start 1.35 1.6)
			(end 1.35 1.249)
			(stroke
				(width 0.15)
				(type solid)
			)
			(layer "F.SilkS")
		)
		(fp_line
			(start -1.351 -1.601)
			(end -0.5 -1.601)
			(stroke
				(width 0.15)
				(type solid)
			)
			(layer "F.SilkS")
		)
		(fp_line
			(start -1.35 -1.601)
			(end -1.35 -1.25)
			(stroke
				(width 0.15)
				(type solid)
			)
			(layer "F.SilkS")
		)
		(fp_line
			(start 1.35 -1.601)
			(end 1.35 -1.25)
			(stroke
				(width 0.15)
				(type solid)
			)
			(layer "F.SilkS")
		)
		(fp_line
			(start 1.35 -1.601)
			(end 0.494 -1.601)
			(stroke
				(width 0.15)
				(type solid)
			)
			(layer "F.SilkS")
		)
		(fp_circle
			(center -0.7 -1.85)
			(end -0.653 -1.85)
			(stroke
				(width 0.15)
				(type solid)
			)
			(fill yes)
			(layer "F.SilkS")
		)
		(fp_rect
			(start -1.85 -2)
			(end 1.8 1.95)
			(stroke
				(width 0.05)
				(type solid)
			)
			(fill no)
			(layer "F.CrtYd")
		)
		(fp_line
			(start -1.25 1.499)
			(end -1.25 -1.25)
			(stroke
				(width 0.15)
				(type solid)
			)
			(layer "F.Fab")
		)
		(fp_line
			(start 1.249 1.499)
			(end -1.25 1.499)
			(stroke
				(width 0.15)
				(type solid)
			)
			(layer "F.Fab")
		)
		(fp_line
			(start -1.25 -1.25)
			(end -1 -1.5)
			(stroke
				(width 0.15)
				(type solid)
			)
			(layer "F.Fab")
		)
		(fp_line
			(start -1 -1.5)
			(end 1.249 -1.5)
			(stroke
				(width 0.15)
				(type solid)
			)
			(layer "F.Fab")
		)
		(fp_line
			(start 1.249 -1.5)
			(end 1.249 1.499)
			(stroke
				(width 0.15)
				(type solid)
			)
			(layer "F.Fab")
		)
		(pad "1" smd oval
			(at -0.25 -1.5 270)
			(size 0.3 0.8)
			(layers "F.Cu" "F.Mask" "F.Paste")
			(net 6 "/Debug FTDI/FTDI_3V3")
			(pinfunction "VCCA")
			(pintype "power_in")
		)
		(pad "2" smd oval
			(at -1.25 -1)
			(size 0.3 0.8)
			(layers "F.Cu" "F.Mask" "F.Paste")
			(net 742 "/Debug FTDI/FTDI_JTAG_TMS")
			(pinfunction "A1")
			(pintype "input")
		)
		(pad "3" smd oval
			(at -1.25 -0.5)
			(size 0.3 0.8)
			(layers "F.Cu" "F.Mask" "F.Paste")
			(net 739 "/Debug FTDI/FTDI_JTAG_TCK")
			(pinfunction "A2")
			(pintype "input")
		)
		(pad "4" smd oval
			(at -1.25 0)
			(size 0.3 0.8)
			(layers "F.Cu" "F.Mask" "F.Paste")
			(net 740 "/Debug FTDI/FTDI_JTAG_TDI")
			(pinfunction "A3")
			(pintype "input")
		)
		(pad "5" smd oval
			(at -1.25 0.494)
			(size 0.3 0.8)
			(layers "F.Cu" "F.Mask" "F.Paste")
			(net 741 "/Debug FTDI/FTDI_JTAG_TDO")
			(pinfunction "A4Y")
			(pintype "output")
		)
		(pad "6" smd oval
			(at -1.25 0.994)
			(size 0.3 0.8)
			(layers "F.Cu" "F.Mask" "F.Paste")
			(net 710 "unconnected-(U7-NC-Pad6)")
			(pinfunction "NC")
			(pintype "no_connect")
		)
		(pad "7" smd oval
			(at -0.25 1.499 270)
			(size 0.3 0.8)
			(layers "F.Cu" "F.Mask" "F.Paste")
			(net 1 "GND")
			(pinfunction "GND")
			(pintype "passive")
		)
		(pad "8" smd oval
			(at 0.244 1.499 270)
			(size 0.3 0.8)
			(layers "F.Cu" "F.Mask" "F.Paste")
			(net 263 "FTDI_DIS")
			(pinfunction "OE")
			(pintype "tri_state")
		)
		(pad "9" smd oval
			(at 1.249 0.994)
			(size 0.3 0.8)
			(layers "F.Cu" "F.Mask" "F.Paste")
			(net 711 "unconnected-(U7-NC-Pad9)")
			(pinfunction "NC")
			(pintype "no_connect")
		)
		(pad "10" smd oval
			(at 1.249 0.494)
			(size 0.3 0.8)
			(layers "F.Cu" "F.Mask" "F.Paste")
			(net 382 "Net-(U7-B4)")
			(pinfunction "B4")
			(pintype "input")
		)
		(pad "11" smd oval
			(at 1.249 0)
			(size 0.3 0.8)
			(layers "F.Cu" "F.Mask" "F.Paste")
			(net 381 "Net-(U7-B3Y)")
			(pinfunction "B3Y")
			(pintype "output")
		)
		(pad "12" smd oval
			(at 1.249 -0.5)
			(size 0.3 0.8)
			(layers "F.Cu" "F.Mask" "F.Paste")
			(net 380 "Net-(U7-B2Y)")
			(pinfunction "B2Y")
			(pintype "output")
		)
		(pad "13" smd oval
			(at 1.249 -1)
			(size 0.3 0.8)
			(layers "F.Cu" "F.Mask" "F.Paste")
			(net 378 "Net-(U7-B1Y)")
			(pinfunction "B1Y")
			(pintype "output")
		)
		(pad "14" smd oval
			(at 0.244 -1.5 270)
			(size 0.3 0.8)
			(layers "F.Cu" "F.Mask" "F.Paste")
			(net 200 "+3V3")
			(pinfunction "VCCB")
			(pintype "power_in")
		)
		(pad "15" smd rect
			(at 0 0 270)
			(size 1 1.5)
			(layers "F.Cu" "F.Mask" "F.Paste")
			(net 1 "GND")
			(pinfunction "GND")
			(pintype "power_in")
		)
	)
)
